# S9S_MB_2U (Grand Teton) — schematic netlist excerpt (pin names and nets, part order shuffled) for the footprints in the layout excerpt that follows; sources: Cadence DE-HDL packaged netlist, KiCad conversion of 03242023_DA0F0TMBIJ0_F0T_Motherboard_J_brd_V01_OCP.brd

R3237  Q_RES  0 5% CHIP  pkg 0402LF  page 154 : A = OCP_SFF_RBT_ARB_OUT ; B = OCP_SFF_RBT_ARB_IN_R
PC495_P1_8  Q_CAP  1UF 16V 10% X6S  pkg C0402  page 288 : A = PVCCIN_CPU1 ; B = GND

(kicad_pcb
	(version 20260206)
	(generator "pcbnew")
	(generator_version "10.0")
	(general
		(thickness 1.6)
		(legacy_teardrops no)
	)
	(paper "A4")
	(title_block
		(title "03242023_DA0F0TMBIJ0_F0T_Motherboard_J_brd_V01_OCP.brd")
		(comment 1 "Grand Teton / footprints 5551-5552 of 6105")
	)
	(layers
		(0 "F.Cu" signal "TOP")
		(4 "In1.Cu" signal "GND")
		(6 "In2.Cu" signal "IN1")
		(8 "In3.Cu" signal "GND1")
		(10 "In4.Cu" signal "IN2")
		(12 "In5.Cu" signal "GND2")
		(14 "In6.Cu" signal "IN3")
		(16 "In7.Cu" signal "GND3")
		(18 "In8.Cu" signal "VCC")
		(20 "In9.Cu" signal "VCC1")
		(22 "In10.Cu" signal "GND4")
		(24 "In11.Cu" signal "IN4")
		(26 "In12.Cu" signal "GND5")
		(28 "In13.Cu" signal "IN5")
		(30 "In14.Cu" signal "GND6")
		(32 "In15.Cu" signal "IN6")
		(34 "In16.Cu" signal "GND7")
		(2 "B.Cu" signal "BOTTOM")
		(9 "F.Adhes" user "F.Adhesive")
		(11 "B.Adhes" user "B.Adhesive")
		(13 "F.Paste" user "Package Geometry/Pastemask Top")
		(15 "B.Paste" user "Package Geometry/Pastemask Bottom")
		(5 "F.SilkS" user "Ref Des/Silkscreen Top")
		(7 "B.SilkS" user "Ref Des/Silkscreen Bottom")
		(1 "F.Mask" user "Board Geometry/Soldermask Top")
		(3 "B.Mask" user "Board Geometry/Soldermask Bottom")
		(17 "Dwgs.User" user "User.Drawings")
		(19 "Cmts.User" user "User.Comments")
		(21 "Eco1.User" user "User.Eco1")
		(23 "Eco2.User" user "User.Eco2")
		(25 "Edge.Cuts" user "Board Geometry/Outline")
		(27 "Margin" user)
		(31 "F.CrtYd" user "Package Geometry/Place Bound Top")
		(29 "B.CrtYd" user "Package Geometry/Place Bound Bottom")
		(35 "F.Fab" user "Ref Des/Assembly Top")
		(33 "B.Fab" user "Ref Des/Assembly Bottom")
	)
	(footprint ""
		(layer "B.Cu")
		(at 191.47409 -78.25613 -90)
		(property "Reference" "R3237"
			(at 0 0 90)
			(layer "B.SilkS")
			(hide yes)
			(effects
				(font
					(size 1.27 1.27)
				)
				(justify mirror)
			)
		)
		(property "Value" ""
			(at 0 0 90)
			(layer "B.Fab")
			(effects
				(font
					(size 1.27 1.27)
				)
				(justify mirror)
			)
		)
		(duplicate_pad_numbers_are_jumpers no)
		(fp_line
			(start -0.7874 0.4064)
			(end 0.7874 0.4064)
			(stroke
				(width 0.1524)
				(type default)
			)
			(layer "B.SilkS")
		)
		(fp_line
			(start 0.7874 0.4064)
			(end 0.7874 -0.4064)
			(stroke
				(width 0.1524)
				(type default)
			)
			(layer "B.SilkS")
		)
		(fp_line
			(start -0.7874 -0.4064)
			(end -0.7874 0.4064)
			(stroke
				(width 0.1524)
				(type default)
			)
			(layer "B.SilkS")
		)
		(fp_line
			(start 0.7874 -0.4064)
			(end -0.7874 -0.4064)
			(stroke
				(width 0.1524)
				(type default)
			)
			(layer "B.SilkS")
		)
		(fp_line
			(start -0.67945 0.3048)
			(end -0.120396 0.3048)
			(stroke
				(width 0.1)
				(type default)
			)
			(layer "B.Fab")
		)
		(fp_line
			(start -0.120396 0.3048)
			(end -0.120396 0.2794)
			(stroke
				(width 0.1)
				(type default)
			)
			(layer "B.Fab")
		)
		(fp_line
			(start 0.12065 0.3048)
			(end 0.67945 0.3048)
			(stroke
				(width 0.1)
				(type default)
			)
			(layer "B.Fab")
		)
		(fp_line
			(start 0.67945 0.3048)
			(end 0.67945 -0.305054)
			(stroke
				(width 0.1)
				(type default)
			)
			(layer "B.Fab")
		)
		(fp_line
			(start -0.120396 0.2794)
			(end 0.12065 0.2794)
			(stroke
				(width 0.1)
				(type default)
			)
			(layer "B.Fab")
		)
		(fp_line
			(start 0.12065 0.2794)
			(end 0.12065 0.3048)
			(stroke
				(width 0.1)
				(type default)
			)
			(layer "B.Fab")
		)
		(fp_line
			(start -0.12065 -0.2794)
			(end -0.12065 -0.3048)
			(stroke
				(width 0.1)
				(type default)
			)
			(layer "B.Fab")
		)
		(fp_line
			(start 0.12065 -0.2794)
			(end -0.12065 -0.2794)
			(stroke
				(width 0.1)
				(type default)
			)
			(layer "B.Fab")
		)
		(fp_line
			(start -0.67945 -0.3048)
			(end -0.67945 0.3048)
			(stroke
				(width 0.1)
				(type default)
			)
			(layer "B.Fab")
		)
		(fp_line
			(start -0.12065 -0.3048)
			(end -0.67945 -0.3048)
			(stroke
				(width 0.1)
				(type default)
			)
			(layer "B.Fab")
		)
		(fp_line
			(start 0.12065 -0.305054)
			(end 0.12065 -0.2794)
			(stroke
				(width 0.1)
				(type default)
			)
			(layer "B.Fab")
		)
		(fp_line
			(start 0.67945 -0.305054)
			(end 0.12065 -0.305054)
			(stroke
				(width 0.1)
				(type default)
			)
			(layer "B.Fab")
		)
		(pad "1" smd rect
			(at 0.40005 0 270)
			(size 0.4572 0.508)
			(layers "B.Cu" "B.Mask" "B.Paste")
			(net "OCP_SFF_RBT_ARB_OUT")
		)
		(pad "2" smd rect
			(at -0.40005 0 270)
			(size 0.4572 0.508)
			(layers "B.Cu" "B.Mask" "B.Paste")
			(net "OCP_SFF_RBT_ARB_IN_R")
		)
	)
	(footprint ""
		(layer "B.Cu")
		(at 134.633208 -333.782924 -90)
		(property "Reference" "PC495_P1_8"
			(at 0 0 90)
			(layer "B.SilkS")
			(hide yes)
			(effects
				(font
					(size 1.27 1.27)
				)
				(justify mirror)
			)
		)
		(property "Value" ""
			(at 0 0 90)
			(layer "B.Fab")
			(effects
				(font
					(size 1.27 1.27)
				)
				(justify mirror)
			)
		)
		(duplicate_pad_numbers_are_jumpers no)
		(fp_line
			(start -0.7874 0.4064)
			(end 0.7874 0.4064)
			(stroke
				(width 0.1524)
				(type default)
			)
			(layer "B.SilkS")
		)
		(fp_line
			(start 0.7874 0.4064)
			(end 0.7874 -0.4064)
			(stroke
				(width 0.1524)
				(type default)
			)
			(layer "B.SilkS")
		)
		(fp_line
			(start -0.7874 -0.4064)
			(end -0.7874 0.4064)
			(stroke
				(width 0.1524)
				(type default)
			)
			(layer "B.SilkS")
		)
		(fp_line
			(start 0.7874 -0.4064)
			(end -0.7874 -0.4064)
			(stroke
				(width 0.1524)
				(type default)
			)
			(layer "B.SilkS")
		)
		(fp_line
			(start -0.67945 0.3048)
			(end -0.120396 0.3048)
			(stroke
				(width 0.1)
				(type default)
			)
			(layer "B.Fab")
		)
		(fp_line
			(start -0.120396 0.3048)
			(end -0.120396 0.2794)
			(stroke
				(width 0.1)
				(type default)
			)
			(layer "B.Fab")
		)
		(fp_line
			(start 0.12065 0.3048)
			(end 0.67945 0.3048)
			(stroke
				(width 0.1)
				(type default)
			)
			(layer "B.Fab")
		)
		(fp_line
			(start 0.67945 0.3048)
			(end 0.67945 -0.305054)
			(stroke
				(width 0.1)
				(type default)
			)
			(layer "B.Fab")
		)
		(fp_line
			(start -0.120396 0.2794)
			(end 0.12065 0.2794)
			(stroke
				(width 0.1)
				(type default)
			)
			(layer "B.Fab")
		)
		(fp_line
			(start 0.12065 0.2794)
			(end 0.12065 0.3048)
			(stroke
				(width 0.1)
				(type default)
			)
			(layer "B.Fab")
		)
		(fp_line
			(start -0.12065 -0.2794)
			(end -0.12065 -0.3048)
			(stroke
				(width 0.1)
				(type default)
			)
			(layer "B.Fab")
		)
		(fp_line
			(start 0.12065 -0.2794)
			(end -0.12065 -0.2794)
			(stroke
				(width 0.1)
				(type default)
			)
			(layer "B.Fab")
		)
		(fp_line
			(start -0.67945 -0.3048)
			(end -0.67945 0.3048)
			(stroke
				(width 0.1)
				(type default)
			)
			(layer "B.Fab")
		)
		(fp_line
			(start -0.12065 -0.3048)
			(end -0.67945 -0.3048)
			(stroke
				(width 0.1)
				(type default)
			)
			(layer "B.Fab")
		)
		(fp_line
			(start 0.12065 -0.305054)
			(end 0.12065 -0.2794)
			(stroke
				(width 0.1)
				(type default)
			)
			(layer "B.Fab")
		)
		(fp_line
			(start 0.67945 -0.305054)
			(end 0.12065 -0.305054)
			(stroke
				(width 0.1)
				(type default)
			)
			(layer "B.Fab")
		)
		(pad "1" smd circle
			(at 0.40005 0 90)
			(size 0 0)
			(layers "B.Cu" "B.Mask" "B.Paste")
			(net "PVCCIN_CPU1")
		)
		(pad "2" smd circle
			(at -0.40005 0 90)
			(size 0 0)
			(layers "B.Cu" "B.Mask" "B.Paste")
			(net "GND")
		)
	)
)
